# T6G (Grand Teton) — schematic netlist excerpt (pin names and nets, part order shuffled) for the footprints in the layout excerpt that follows; sources: Cadence DE-HDL packaged netlist, KiCad conversion of 04192023_DAF0TMB3IC0_F0TG_MB_C_brd_V02_OCP.brd

PC153_6  Q_CAP  0.1UF 25V 10% X7R  pkg 0402  page 196 : A = SW_P12V_AUX_PVDDCR_CPU0_P0_FLT ; B = GND
R492  Q_RES  4.7K 5% CHIP  pkg 0402LF  page 188 : A = P3V3_AUX ; B = PWRGD_P5V_R_N

(kicad_pcb
	(version 20260206)
	(generator "pcbnew")
	(generator_version "10.0")
	(general
		(thickness 1.6)
		(legacy_teardrops no)
	)
	(paper "A4")
	(title_block
		(title "04192023_DAF0TMB3IC0_F0TG_MB_C_brd_V02_OCP.brd")
		(comment 1 "Grand Teton / footprints 3499-3500 of 8354")
	)
	(layers
		(0 "F.Cu" signal "TOP")
		(4 "In1.Cu" signal "GND")
		(6 "In2.Cu" signal "IN1")
		(8 "In3.Cu" signal "GND1")
		(10 "In4.Cu" signal "IN2")
		(12 "In5.Cu" signal "GND2")
		(14 "In6.Cu" signal "IN3")
		(16 "In7.Cu" signal "GND3")
		(18 "In8.Cu" signal "VCC")
		(20 "In9.Cu" signal "VCC1")
		(22 "In10.Cu" signal "GND4")
		(24 "In11.Cu" signal "IN4")
		(26 "In12.Cu" signal "GND5")
		(28 "In13.Cu" signal "IN5")
		(30 "In14.Cu" signal "GND6")
		(32 "In15.Cu" signal "IN6")
		(34 "In16.Cu" signal "GND7")
		(2 "B.Cu" signal "BOTTOM")
		(9 "F.Adhes" user "F.Adhesive")
		(11 "B.Adhes" user "B.Adhesive")
		(13 "F.Paste" user "Package Geometry/Pastemask Top")
		(15 "B.Paste" user "Package Geometry/Pastemask Bottom")
		(5 "F.SilkS" user "Ref Des/Silkscreen Top")
		(7 "B.SilkS" user "Ref Des/Silkscreen Bottom")
		(1 "F.Mask" user "Board Geometry/Soldermask Top")
		(3 "B.Mask" user "Board Geometry/Soldermask Bottom")
		(17 "Dwgs.User" user "User.Drawings")
		(19 "Cmts.User" user "User.Comments")
		(21 "Eco1.User" user "User.Eco1")
		(23 "Eco2.User" user "User.Eco2")
		(25 "Edge.Cuts" user "Board Geometry/Outline")
		(27 "Margin" user)
		(31 "F.CrtYd" user "Package Geometry/Place Bound Top")
		(29 "B.CrtYd" user "Package Geometry/Place Bound Bottom")
		(35 "F.Fab" user "Ref Des/Assembly Top")
		(33 "B.Fab" user "Ref Des/Assembly Bottom")
	)
	(footprint ""
		(layer "F.Cu")
		(at 342.966294 -161.056574 90)
		(property "Reference" "PC153_6"
			(at 0 0 90)
			(layer "F.SilkS")
			(hide yes)
			(effects
				(font
					(size 1.27 1.27)
				)
			)
		)
		(property "Value" ""
			(at 0 0 90)
			(layer "F.Fab")
			(effects
				(font
					(size 1.27 1.27)
				)
			)
		)
		(duplicate_pad_numbers_are_jumpers no)
		(fp_line
			(start 0.7874 -0.4064)
			(end 0.7874 0.4064)
			(stroke
				(width 0.1524)
				(type default)
			)
			(layer "F.SilkS")
		)
		(fp_line
			(start -0.7874 -0.4064)
			(end 0.7874 -0.4064)
			(stroke
				(width 0.1524)
				(type default)
			)
			(layer "F.SilkS")
		)
		(fp_line
			(start 0.7874 0.4064)
			(end -0.7874 0.4064)
			(stroke
				(width 0.1524)
				(type default)
			)
			(layer "F.SilkS")
		)
		(fp_line
			(start -0.7874 0.4064)
			(end -0.7874 -0.4064)
			(stroke
				(width 0.1524)
				(type default)
			)
			(layer "F.SilkS")
		)
		(fp_line
			(start -0.12065 -0.305054)
			(end -0.12065 -0.2794)
			(stroke
				(width 0.1)
				(type default)
			)
			(layer "F.Fab")
		)
		(fp_line
			(start -0.67945 -0.305054)
			(end -0.12065 -0.305054)
			(stroke
				(width 0.1)
				(type default)
			)
			(layer "F.Fab")
		)
		(fp_line
			(start 0.67945 -0.3048)
			(end 0.67945 0.3048)
			(stroke
				(width 0.1)
				(type default)
			)
			(layer "F.Fab")
		)
		(fp_line
			(start 0.12065 -0.3048)
			(end 0.67945 -0.3048)
			(stroke
				(width 0.1)
				(type default)
			)
			(layer "F.Fab")
		)
		(fp_line
			(start 0.12065 -0.2794)
			(end 0.12065 -0.3048)
			(stroke
				(width 0.1)
				(type default)
			)
			(layer "F.Fab")
		)
		(fp_line
			(start -0.12065 -0.2794)
			(end 0.12065 -0.2794)
			(stroke
				(width 0.1)
				(type default)
			)
			(layer "F.Fab")
		)
		(fp_line
			(start 0.120396 0.2794)
			(end -0.12065 0.2794)
			(stroke
				(width 0.1)
				(type default)
			)
			(layer "F.Fab")
		)
		(fp_line
			(start -0.12065 0.2794)
			(end -0.12065 0.3048)
			(stroke
				(width 0.1)
				(type default)
			)
			(layer "F.Fab")
		)
		(fp_line
			(start 0.67945 0.3048)
			(end 0.120396 0.3048)
			(stroke
				(width 0.1)
				(type default)
			)
			(layer "F.Fab")
		)
		(fp_line
			(start 0.120396 0.3048)
			(end 0.120396 0.2794)
			(stroke
				(width 0.1)
				(type default)
			)
			(layer "F.Fab")
		)
		(fp_line
			(start -0.12065 0.3048)
			(end -0.67945 0.3048)
			(stroke
				(width 0.1)
				(type default)
			)
			(layer "F.Fab")
		)
		(fp_line
			(start -0.67945 0.3048)
			(end -0.67945 -0.305054)
			(stroke
				(width 0.1)
				(type default)
			)
			(layer "F.Fab")
		)
		(pad "1" smd circle
			(at -0.40005 0 90)
			(size 0 0)
			(layers "F.Cu" "F.Mask" "F.Paste")
			(net "SW_P12V_AUX_PVDDCR_CPU0_P0_FLT")
		)
		(pad "2" smd circle
			(at 0.40005 0 90)
			(size 0 0)
			(layers "F.Cu" "F.Mask" "F.Paste")
			(net "GND")
		)
	)
	(footprint ""
		(layer "F.Cu")
		(at 166.624 -131.953 -90)
		(property "Reference" "R492"
			(at 0 0 270)
			(layer "F.SilkS")
			(hide yes)
			(effects
				(font
					(size 1.27 1.27)
				)
			)
		)
		(property "Value" ""
			(at 0 0 270)
			(layer "F.Fab")
			(effects
				(font
					(size 1.27 1.27)
				)
			)
		)
		(duplicate_pad_numbers_are_jumpers no)
		(fp_line
			(start -0.7874 0.4064)
			(end -0.7874 -0.4064)
			(stroke
				(width 0.1524)
				(type default)
			)
			(layer "F.SilkS")
		)
		(fp_line
			(start 0.7874 0.4064)
			(end -0.7874 0.4064)
			(stroke
				(width 0.1524)
				(type default)
			)
			(layer "F.SilkS")
		)
		(fp_line
			(start -0.7874 -0.4064)
			(end 0.7874 -0.4064)
			(stroke
				(width 0.1524)
				(type default)
			)
			(layer "F.SilkS")
		)
		(fp_line
			(start 0.7874 -0.4064)
			(end 0.7874 0.4064)
			(stroke
				(width 0.1524)
				(type default)
			)
			(layer "F.SilkS")
		)
		(fp_line
			(start -0.67945 0.3048)
			(end -0.67945 -0.305054)
			(stroke
				(width 0.1)
				(type default)
			)
			(layer "F.Fab")
		)
		(fp_line
			(start -0.12065 0.3048)
			(end -0.67945 0.3048)
			(stroke
				(width 0.1)
				(type default)
			)
			(layer "F.Fab")
		)
		(fp_line
			(start 0.120396 0.3048)
			(end 0.120396 0.2794)
			(stroke
				(width 0.1)
				(type default)
			)
			(layer "F.Fab")
		)
		(fp_line
			(start 0.67945 0.3048)
			(end 0.120396 0.3048)
			(stroke
				(width 0.1)
				(type default)
			)
			(layer "F.Fab")
		)
		(fp_line
			(start -0.12065 0.2794)
			(end -0.12065 0.3048)
			(stroke
				(width 0.1)
				(type default)
			)
			(layer "F.Fab")
		)
		(fp_line
			(start 0.120396 0.2794)
			(end -0.12065 0.2794)
			(stroke
				(width 0.1)
				(type default)
			)
			(layer "F.Fab")
		)
		(fp_line
			(start -0.12065 -0.2794)
			(end 0.12065 -0.2794)
			(stroke
				(width 0.1)
				(type default)
			)
			(layer "F.Fab")
		)
		(fp_line
			(start 0.12065 -0.2794)
			(end 0.12065 -0.3048)
			(stroke
				(width 0.1)
				(type default)
			)
			(layer "F.Fab")
		)
		(fp_line
			(start 0.12065 -0.3048)
			(end 0.67945 -0.3048)
			(stroke
				(width 0.1)
				(type default)
			)
			(layer "F.Fab")
		)
		(fp_line
			(start 0.67945 -0.3048)
			(end 0.67945 0.3048)
			(stroke
				(width 0.1)
				(type default)
			)
			(layer "F.Fab")
		)
		(fp_line
			(start -0.67945 -0.305054)
			(end -0.12065 -0.305054)
			(stroke
				(width 0.1)
				(type default)
			)
			(layer "F.Fab")
		)
		(fp_line
			(start -0.12065 -0.305054)
			(end -0.12065 -0.2794)
			(stroke
				(width 0.1)
				(type default)
			)
			(layer "F.Fab")
		)
		(pad "1" smd circle
			(at -0.40005 0 270)
			(size 0 0)
			(layers "F.Cu" "F.Mask" "F.Paste")
			(net "P3V3_AUX")
		)
		(pad "2" smd circle
			(at 0.40005 0 270)
			(size 0 0)
			(layers "F.Cu" "F.Mask" "F.Paste")
			(net "PWRGD_P5V_R_N")
		)
	)
)
